(kicad_pcb
	(version 20260206)
	(generator "pcbnew")
	(generator_version "10.0")
	(general
		(thickness 1.6)
		(legacy_teardrops no)
	)
	(paper "A4")
	(title_block
		(title "v1-chassis-manager — T6M_CM_d_v01_1031_1645.brd")
		(comment 1 "Open CloudServer (Microsoft) / footprints 326-335 of 2512")
	)
	(layers
		(0 "F.Cu" signal "TOP")
		(4 "In1.Cu" signal "GND1")
		(6 "In2.Cu" signal "IN1")
		(8 "In3.Cu" signal "VCC1")
		(10 "In4.Cu" signal "VCC2")
		(12 "In5.Cu" signal "GND2")
		(14 "In6.Cu" signal "IN2")
		(16 "In7.Cu" signal "IN3")
		(18 "In8.Cu" signal "GND3")
		(2 "B.Cu" signal "BOTTOM")
		(9 "F.Adhes" user "F.Adhesive")
		(11 "B.Adhes" user "B.Adhesive")
		(13 "F.Paste" user "Package Geometry/Pastemask Top")
		(15 "B.Paste" user "Package Geometry/Pastemask Bottom")
		(5 "F.SilkS" user "Ref Des/Silkscreen Top")
		(7 "B.SilkS" user "Ref Des/Silkscreen Bottom")
		(1 "F.Mask" user "Board Geometry/Soldermask Top")
		(3 "B.Mask" user "Board Geometry/Soldermask Bottom")
		(17 "Dwgs.User" user "User.Drawings")
		(19 "Cmts.User" user "User.Comments")
		(21 "Eco1.User" user "User.Eco1")
		(23 "Eco2.User" user "User.Eco2")
		(25 "Edge.Cuts" user "Board Geometry/Outline")
		(27 "Margin" user)
		(31 "F.CrtYd" user "Package Geometry/Place Bound Top")
		(29 "B.CrtYd" user "Package Geometry/Place Bound Bottom")
		(35 "F.Fab" user "Ref Des/Assembly Top")
		(33 "B.Fab" user "Ref Des/Assembly Bottom")
	)
	(footprint ""
		(layer "F.Cu")
		(at 116.894864 -26.094944 180)
		(property "Reference" "R1124"
			(at -1.468882 0.263398 90)
			(unlocked yes)
			(layer "F.SilkS")
			(effects
				(font
					(size 0.7874 0.5842)
					(thickness 0.1524)
				)
				(justify left)
			)
		)
		(property "Value" ""
			(at 0 0 180)
			(layer "F.Fab")
			(effects
				(font
					(size 1.27 1.27)
				)
			)
		)
		(duplicate_pad_numbers_are_jumpers no)
		(fp_line
			(start 0.7874 0.4064)
			(end -0.7874 0.4064)
			(stroke
				(width 0.1524)
				(type default)
			)
			(layer "F.SilkS")
		)
		(fp_line
			(start 0.7874 -0.4064)
			(end 0.7874 0.4064)
			(stroke
				(width 0.1524)
				(type default)
			)
			(layer "F.SilkS")
		)
		(fp_line
			(start -0.7874 0.4064)
			(end -0.7874 -0.4064)
			(stroke
				(width 0.1524)
				(type default)
			)
			(layer "F.SilkS")
		)
		(fp_line
			(start -0.7874 -0.4064)
			(end 0.7874 -0.4064)
			(stroke
				(width 0.1524)
				(type default)
			)
			(layer "F.SilkS")
		)
		(fp_poly
			(pts
				(xy -0.508 0.2794) (xy -0.508 0.2286) (xy -0.635 0.2286) (xy -0.635 -0.254) (xy -0.5334 -0.254)
				(xy -0.5334 -0.2794) (xy 0.5334 -0.2794) (xy 0.5334 -0.254) (xy 0.635 -0.254) (xy 0.635 0.254) (xy 0.5334 0.254)
				(xy 0.5334 0.2794)
			)
			(stroke
				(width 0)
				(type default)
			)
			(fill no)
			(layer "F.CrtYd")
		)
		(pad "1" smd rect
			(at 0.40005 0 180)
			(size 0.4572 0.508)
			(layers "F.Cu" "F.Mask" "F.Paste")
			(net "PV_VDDR_NODE1")
		)
		(pad "2" smd rect
			(at -0.40005 0 180)
			(size 0.4572 0.508)
			(layers "F.Cu" "F.Mask" "F.Paste")
			(net "PV_VTT_DDR_NODE1_REFIN")
		)
	)
	(footprint ""
		(layer "F.Cu")
		(at 155.05176 -188.126624 90)
		(property "Reference" "C660"
			(at 5.519674 -3.327908 90)
			(unlocked yes)
			(layer "F.SilkS")
			(effects
				(font
					(size 0.7874 0.5842)
					(thickness 0.1524)
				)
				(justify left)
			)
		)
		(property "Value" ""
			(at 0 0 90)
			(layer "F.Fab")
			(effects
				(font
					(size 1.27 1.27)
				)
			)
		)
		(duplicate_pad_numbers_are_jumpers no)
		(fp_line
			(start 0.7874 -0.4064)
			(end 0.7874 0.4064)
			(stroke
				(width 0.1524)
				(type default)
			)
			(layer "F.SilkS")
		)
		(fp_line
			(start -0.7874 -0.4064)
			(end 0.7874 -0.4064)
			(stroke
				(width 0.1524)
				(type default)
			)
			(layer "F.SilkS")
		)
		(fp_line
			(start 0 0.381)
			(end 0 -0.381)
			(stroke
				(width 0.1524)
				(type default)
			)
			(layer "F.SilkS")
		)
		(fp_line
			(start 0.7874 0.4064)
			(end -0.7874 0.4064)
			(stroke
				(width 0.1524)
				(type default)
			)
			(layer "F.SilkS")
		)
		(fp_line
			(start -0.7874 0.4064)
			(end -0.7874 -0.4064)
			(stroke
				(width 0.1524)
				(type default)
			)
			(layer "F.SilkS")
		)
		(fp_poly
			(pts
				(xy -0.5334 0.254) (xy -0.635 0.254) (xy -0.635 0.2286) (xy -0.635 -0.254) (xy -0.5334 -0.254) (xy -0.5334 -0.2794)
				(xy 0.5334 -0.2794) (xy 0.5334 -0.254) (xy 0.635 -0.254) (xy 0.635 0.254) (xy 0.5334 0.254) (xy 0.5334 0.2794)
				(xy -0.508 0.2794) (xy -0.5334 0.2794)
			)
			(stroke
				(width 0)
				(type default)
			)
			(fill no)
			(layer "F.CrtYd")
		)
		(pad "1" smd rect
			(at 0.40005 0 90)
			(size 0.4572 0.508)
			(layers "F.Cu" "F.Mask" "F.Paste")
			(net "T12_NODE1_EN_R")
		)
		(pad "2" smd rect
			(at -0.40005 0 90)
			(size 0.4572 0.508)
			(layers "F.Cu" "F.Mask" "F.Paste")
			(net "GND")
		)
	)
	(footprint ""
		(layer "F.Cu")
		(at 77.841602 -5.105654 90)
		(property "Reference" "PL17"
			(at 4.08686 1.526794 0)
			(unlocked yes)
			(layer "F.SilkS")
			(effects
				(font
					(size 0.7874 0.5842)
					(thickness 0.1524)
				)
				(justify left)
			)
		)
		(property "Value" ""
			(at 0 0 90)
			(layer "F.Fab")
			(effects
				(font
					(size 1.27 1.27)
				)
			)
		)
		(duplicate_pad_numbers_are_jumpers no)
		(fp_line
			(start 3.350006 -4.1656)
			(end 3.350006 4.1656)
			(stroke
				(width 0.1524)
				(type default)
			)
			(layer "F.SilkS")
		)
		(fp_line
			(start -3.350006 -4.1656)
			(end 3.350006 -4.1656)
			(stroke
				(width 0.1524)
				(type default)
			)
			(layer "F.SilkS")
		)
		(fp_line
			(start 3.350006 4.1656)
			(end -3.350006 4.1656)
			(stroke
				(width 0.1524)
				(type default)
			)
			(layer "F.SilkS")
		)
		(fp_line
			(start -3.350006 4.1656)
			(end -3.350006 -4.1656)
			(stroke
				(width 0.1524)
				(type default)
			)
			(layer "F.SilkS")
		)
		(fp_poly
			(pts
				(xy -3.350006 -3.64998) (xy -1.7018 -3.64998) (xy -1.7018 -4.05257) (xy 1.7018 -4.05257) (xy 1.7018 -3.64998)
				(xy 3.350006 -3.64998) (xy 3.350006 3.64998) (xy 1.7018 3.64998) (xy 1.7018 4.05257) (xy -1.7018 4.05257)
				(xy -1.7018 3.64998) (xy -3.350006 3.64998)
			)
			(stroke
				(width 0)
				(type default)
			)
			(fill no)
			(layer "F.CrtYd")
		)
		(fp_line
			(start 3.350006 -3.64998)
			(end 3.350006 3.64998)
			(stroke
				(width 0.1)
				(type default)
			)
			(layer "F.Fab")
		)
		(fp_line
			(start -3.350006 -3.64998)
			(end 3.350006 -3.64998)
			(stroke
				(width 0.1)
				(type default)
			)
			(layer "F.Fab")
		)
		(fp_line
			(start 3.350006 3.64998)
			(end -3.350006 3.64998)
			(stroke
				(width 0.1)
				(type default)
			)
			(layer "F.Fab")
		)
		(fp_line
			(start -3.350006 3.64998)
			(end -3.350006 -3.64998)
			(stroke
				(width 0.1)
				(type default)
			)
			(layer "F.Fab")
		)
		(pad "1" smd rect
			(at 0 -2.92481)
			(size 2.15392 3.302)
			(layers "F.Cu" "F.Mask" "F.Paste")
			(net "SW_P3V3_NODE1_PH")
		)
		(pad "2" smd rect
			(at 0 2.92481)
			(size 2.15392 3.302)
			(layers "F.Cu" "F.Mask" "F.Paste")
			(net "P3V3_NODE1")
		)
	)
	(footprint ""
		(layer "F.Cu")
		(at 91.102434 -188.858398 180)
		(property "Reference" "C672"
			(at 1.437894 7.241032 0)
			(unlocked yes)
			(layer "F.SilkS")
			(effects
				(font
					(size 0.7874 0.5842)
					(thickness 0.1524)
				)
				(justify left)
			)
		)
		(property "Value" ""
			(at 0 0 180)
			(layer "F.Fab")
			(effects
				(font
					(size 1.27 1.27)
				)
			)
		)
		(duplicate_pad_numbers_are_jumpers no)
		(fp_line
			(start 0.7874 0.4064)
			(end -0.7874 0.4064)
			(stroke
				(width 0.1524)
				(type default)
			)
			(layer "F.SilkS")
		)
		(fp_line
			(start 0.7874 -0.4064)
			(end 0.7874 0.4064)
			(stroke
				(width 0.1524)
				(type default)
			)
			(layer "F.SilkS")
		)
		(fp_line
			(start 0 0.381)
			(end 0 -0.381)
			(stroke
				(width 0.1524)
				(type default)
			)
			(layer "F.SilkS")
		)
		(fp_line
			(start -0.7874 0.4064)
			(end -0.7874 -0.4064)
			(stroke
				(width 0.1524)
				(type default)
			)
			(layer "F.SilkS")
		)
		(fp_line
			(start -0.7874 -0.4064)
			(end 0.7874 -0.4064)
			(stroke
				(width 0.1524)
				(type default)
			)
			(layer "F.SilkS")
		)
		(fp_poly
			(pts
				(xy -0.5334 0.254) (xy -0.635 0.254) (xy -0.635 0.2286) (xy -0.635 -0.254) (xy -0.5334 -0.254) (xy -0.5334 -0.2794)
				(xy 0.5334 -0.2794) (xy 0.5334 -0.254) (xy 0.635 -0.254) (xy 0.635 0.254) (xy 0.5334 0.254) (xy 0.5334 0.2794)
				(xy -0.508 0.2794) (xy -0.5334 0.2794)
			)
			(stroke
				(width 0)
				(type default)
			)
			(fill no)
			(layer "F.CrtYd")
		)
		(pad "1" smd rect
			(at 0.40005 0 180)
			(size 0.4572 0.508)
			(layers "F.Cu" "F.Mask" "F.Paste")
			(net "UART_T5_NODE1_RXD")
		)
		(pad "2" smd rect
			(at -0.40005 0 180)
			(size 0.4572 0.508)
			(layers "F.Cu" "F.Mask" "F.Paste")
			(net "GND")
		)
	)
	(footprint ""
		(layer "F.Cu")
		(at 10.640568 -167.373554)
		(property "Reference" "C542"
			(at 0.4699 -1.475486 0)
			(unlocked yes)
			(layer "F.SilkS")
			(effects
				(font
					(size 0.7874 0.5842)
					(thickness 0.1524)
				)
				(justify left)
			)
		)
		(property "Value" ""
			(at 0 0 0)
			(layer "F.Fab")
			(effects
				(font
					(size 1.27 1.27)
				)
			)
		)
		(duplicate_pad_numbers_are_jumpers no)
		(fp_line
			(start -0.7874 -0.4064)
			(end 0.7874 -0.4064)
			(stroke
				(width 0.1524)
				(type default)
			)
			(layer "F.SilkS")
		)
		(fp_line
			(start -0.7874 0.4064)
			(end -0.7874 -0.4064)
			(stroke
				(width 0.1524)
				(type default)
			)
			(layer "F.SilkS")
		)
		(fp_line
			(start 0 0.381)
			(end 0 -0.381)
			(stroke
				(width 0.1524)
				(type default)
			)
			(layer "F.SilkS")
		)
		(fp_line
			(start 0.7874 -0.4064)
			(end 0.7874 0.4064)
			(stroke
				(width 0.1524)
				(type default)
			)
			(layer "F.SilkS")
		)
		(fp_line
			(start 0.7874 0.4064)
			(end -0.7874 0.4064)
			(stroke
				(width 0.1524)
				(type default)
			)
			(layer "F.SilkS")
		)
		(fp_poly
			(pts
				(xy -0.5334 0.254) (xy -0.635 0.254) (xy -0.635 0.2286) (xy -0.635 -0.254) (xy -0.5334 -0.254) (xy -0.5334 -0.2794)
				(xy 0.5334 -0.2794) (xy 0.5334 -0.254) (xy 0.635 -0.254) (xy 0.635 0.254) (xy 0.5334 0.254) (xy 0.5334 0.2794)
				(xy -0.508 0.2794) (xy -0.5334 0.2794)
			)
			(stroke
				(width 0)
				(type default)
			)
			(fill no)
			(layer "F.CrtYd")
		)
		(pad "1" smd rect
			(at 0.40005 0)
			(size 0.4572 0.508)
			(layers "F.Cu" "F.Mask" "F.Paste")
			(net "N54258523")
		)
		(pad "2" smd rect
			(at -0.40005 0)
			(size 0.4572 0.508)
			(layers "F.Cu" "F.Mask" "F.Paste")
			(net "N54258525")
		)
	)
	(footprint ""
		(layer "F.Cu")
		(at 187.7695 -166.072566)
		(property "Reference" "R1280"
			(at -1.634744 5.208778 0)
			(unlocked yes)
			(layer "F.SilkS")
			(effects
				(font
					(size 0.7874 0.5842)
					(thickness 0.1524)
				)
				(justify left)
			)
		)
		(property "Value" ""
			(at 0 0 0)
			(layer "F.Fab")
			(effects
				(font
					(size 1.27 1.27)
				)
			)
		)
		(duplicate_pad_numbers_are_jumpers no)
		(fp_line
			(start -0.7874 -0.4064)
			(end 0.7874 -0.4064)
			(stroke
				(width 0.1524)
				(type default)
			)
			(layer "F.SilkS")
		)
		(fp_line
			(start -0.7874 0.4064)
			(end -0.7874 -0.4064)
			(stroke
				(width 0.1524)
				(type default)
			)
			(layer "F.SilkS")
		)
		(fp_line
			(start 0.7874 -0.4064)
			(end 0.7874 0.4064)
			(stroke
				(width 0.1524)
				(type default)
			)
			(layer "F.SilkS")
		)
		(fp_line
			(start 0.7874 0.4064)
			(end -0.7874 0.4064)
			(stroke
				(width 0.1524)
				(type default)
			)
			(layer "F.SilkS")
		)
		(fp_poly
			(pts
				(xy -0.508 0.2794) (xy -0.508 0.2286) (xy -0.635 0.2286) (xy -0.635 -0.254) (xy -0.5334 -0.254)
				(xy -0.5334 -0.2794) (xy 0.5334 -0.2794) (xy 0.5334 -0.254) (xy 0.635 -0.254) (xy 0.635 0.254) (xy 0.5334 0.254)
				(xy 0.5334 0.2794)
			)
			(stroke
				(width 0)
				(type default)
			)
			(fill no)
			(layer "F.CrtYd")
		)
		(pad "1" smd rect
			(at 0.40005 0)
			(size 0.4572 0.508)
			(layers "F.Cu" "F.Mask" "F.Paste")
			(net "N54134271")
		)
		(pad "2" smd rect
			(at -0.40005 0)
			(size 0.4572 0.508)
			(layers "F.Cu" "F.Mask" "F.Paste")
			(net "LAN2_P4_R")
		)
	)
	(footprint ""
		(layer "F.Cu")
		(at 57.081166 -96.709992 90)
		(property "Reference" "R82"
			(at -54.98719 28.432252 90)
			(unlocked yes)
			(layer "F.SilkS")
			(effects
				(font
					(size 0.7874 0.5842)
					(thickness 0.1524)
				)
				(justify left)
			)
		)
		(property "Value" ""
			(at 0 0 90)
			(layer "F.Fab")
			(effects
				(font
					(size 1.27 1.27)
				)
			)
		)
		(duplicate_pad_numbers_are_jumpers no)
		(fp_line
			(start 0.7874 -0.4064)
			(end 0.7874 0.4064)
			(stroke
				(width 0.1524)
				(type default)
			)
			(layer "F.SilkS")
		)
		(fp_line
			(start -0.7874 -0.4064)
			(end 0.7874 -0.4064)
			(stroke
				(width 0.1524)
				(type default)
			)
			(layer "F.SilkS")
		)
		(fp_line
			(start 0.7874 0.4064)
			(end -0.7874 0.4064)
			(stroke
				(width 0.1524)
				(type default)
			)
			(layer "F.SilkS")
		)
		(fp_line
			(start -0.7874 0.4064)
			(end -0.7874 -0.4064)
			(stroke
				(width 0.1524)
				(type default)
			)
			(layer "F.SilkS")
		)
		(fp_poly
			(pts
				(xy -0.508 0.2794) (xy -0.508 0.2286) (xy -0.635 0.2286) (xy -0.635 -0.254) (xy -0.5334 -0.254)
				(xy -0.5334 -0.2794) (xy 0.5334 -0.2794) (xy 0.5334 -0.254) (xy 0.635 -0.254) (xy 0.635 0.254) (xy 0.5334 0.254)
				(xy 0.5334 0.2794)
			)
			(stroke
				(width 0)
				(type default)
			)
			(fill no)
			(layer "F.CrtYd")
		)
		(pad "1" smd rect
			(at 0.40005 0 90)
			(size 0.4572 0.508)
			(layers "F.Cu" "F.Mask" "F.Paste")
			(net "GND")
		)
		(pad "2" smd rect
			(at -0.40005 0 90)
			(size 0.4572 0.508)
			(layers "F.Cu" "F.Mask" "F.Paste")
			(net "PD_CPU_NODE1_DFX_GPIO_GRP0_3")
		)
	)
	(footprint ""
		(layer "F.Cu")
		(at 14.052804 -164.700712 180)
		(property "Reference" "R1276"
			(at 1.765808 2.226056 0)
			(unlocked yes)
			(layer "F.SilkS")
			(effects
				(font
					(size 0.7874 0.5842)
					(thickness 0.1524)
				)
				(justify left)
			)
		)
		(property "Value" ""
			(at 0 0 180)
			(layer "F.Fab")
			(effects
				(font
					(size 1.27 1.27)
				)
			)
		)
		(duplicate_pad_numbers_are_jumpers no)
		(fp_line
			(start 0.7874 0.4064)
			(end -0.7874 0.4064)
			(stroke
				(width 0.1524)
				(type default)
			)
			(layer "F.SilkS")
		)
		(fp_line
			(start 0.7874 -0.4064)
			(end 0.7874 0.4064)
			(stroke
				(width 0.1524)
				(type default)
			)
			(layer "F.SilkS")
		)
		(fp_line
			(start -0.7874 0.4064)
			(end -0.7874 -0.4064)
			(stroke
				(width 0.1524)
				(type default)
			)
			(layer "F.SilkS")
		)
		(fp_line
			(start -0.7874 -0.4064)
			(end 0.7874 -0.4064)
			(stroke
				(width 0.1524)
				(type default)
			)
			(layer "F.SilkS")
		)
		(fp_poly
			(pts
				(xy -0.508 0.2794) (xy -0.508 0.2286) (xy -0.635 0.2286) (xy -0.635 -0.254) (xy -0.5334 -0.254)
				(xy -0.5334 -0.2794) (xy 0.5334 -0.2794) (xy 0.5334 -0.254) (xy 0.635 -0.254) (xy 0.635 0.254) (xy 0.5334 0.254)
				(xy 0.5334 0.2794)
			)
			(stroke
				(width 0)
				(type default)
			)
			(fill no)
			(layer "F.CrtYd")
		)
		(pad "1" smd rect
			(at 0.40005 0 180)
			(size 0.4572 0.508)
			(layers "F.Cu" "F.Mask" "F.Paste")
			(net "N54065132")
		)
		(pad "2" smd rect
			(at -0.40005 0 180)
			(size 0.4572 0.508)
			(layers "F.Cu" "F.Mask" "F.Paste")
			(net "LAN1_P4_R")
		)
	)
	(footprint ""
		(layer "F.Cu")
		(at 34.457894 -9.954514)
		(property "Reference" "PR38"
			(at -10.749788 -0.098044 0)
			(unlocked yes)
			(layer "F.SilkS")
			(effects
				(font
					(size 0.7874 0.5842)
					(thickness 0.1524)
				)
				(justify left)
			)
		)
		(property "Value" ""
			(at 0 0 0)
			(layer "F.Fab")
			(effects
				(font
					(size 1.27 1.27)
				)
			)
		)
		(duplicate_pad_numbers_are_jumpers no)
		(fp_line
			(start -0.7874 -0.4064)
			(end 0.7874 -0.4064)
			(stroke
				(width 0.1524)
				(type default)
			)
			(layer "F.SilkS")
		)
		(fp_line
			(start -0.7874 0.4064)
			(end -0.7874 -0.4064)
			(stroke
				(width 0.1524)
				(type default)
			)
			(layer "F.SilkS")
		)
		(fp_line
			(start 0.7874 -0.4064)
			(end 0.7874 0.4064)
			(stroke
				(width 0.1524)
				(type default)
			)
			(layer "F.SilkS")
		)
		(fp_line
			(start 0.7874 0.4064)
			(end -0.7874 0.4064)
			(stroke
				(width 0.1524)
				(type default)
			)
			(layer "F.SilkS")
		)
		(fp_poly
			(pts
				(xy -0.508 0.2794) (xy -0.508 0.2286) (xy -0.635 0.2286) (xy -0.635 -0.254) (xy -0.5334 -0.254)
				(xy -0.5334 -0.2794) (xy 0.5334 -0.2794) (xy 0.5334 -0.254) (xy 0.635 -0.254) (xy 0.635 0.254) (xy 0.5334 0.254)
				(xy 0.5334 0.2794)
			)
			(stroke
				(width 0)
				(type default)
			)
			(fill no)
			(layer "F.CrtYd")
		)
		(pad "1" smd rect
			(at 0.40005 0)
			(size 0.4572 0.508)
			(layers "F.Cu" "F.Mask" "F.Paste")
			(net "PV_VDDR_NODE1_V1")
		)
		(pad "2" smd rect
			(at -0.40005 0)
			(size 0.4572 0.508)
			(layers "F.Cu" "F.Mask" "F.Paste")
			(net "PV_VDDR_NODE1_V0")
		)
	)
	(footprint ""
		(layer "F.Cu")
		(at 165.011354 -185.083196 180)
		(property "Reference" "R1171"
			(at 4.864354 0.538734 0)
			(unlocked yes)
			(layer "F.SilkS")
			(effects
				(font
					(size 0.7874 0.5842)
					(thickness 0.1524)
				)
				(justify left)
			)
		)
		(property "Value" ""
			(at 0 0 180)
			(layer "F.Fab")
			(effects
				(font
					(size 1.27 1.27)
				)
			)
		)
		(duplicate_pad_numbers_are_jumpers no)
		(fp_line
			(start 0.7874 0.4064)
			(end -0.7874 0.4064)
			(stroke
				(width 0.1524)
				(type default)
			)
			(layer "F.SilkS")
		)
		(fp_line
			(start 0.7874 -0.4064)
			(end 0.7874 0.4064)
			(stroke
				(width 0.1524)
				(type default)
			)
			(layer "F.SilkS")
		)
		(fp_line
			(start -0.7874 0.4064)
			(end -0.7874 -0.4064)
			(stroke
				(width 0.1524)
				(type default)
			)
			(layer "F.SilkS")
		)
		(fp_line
			(start -0.7874 -0.4064)
			(end 0.7874 -0.4064)
			(stroke
				(width 0.1524)
				(type default)
			)
			(layer "F.SilkS")
		)
		(fp_poly
			(pts
				(xy -0.508 0.2794) (xy -0.508 0.2286) (xy -0.635 0.2286) (xy -0.635 -0.254) (xy -0.5334 -0.254)
				(xy -0.5334 -0.2794) (xy 0.5334 -0.2794) (xy 0.5334 -0.254) (xy 0.635 -0.254) (xy 0.635 0.254) (xy 0.5334 0.254)
				(xy 0.5334 0.2794)
			)
			(stroke
				(width 0)
				(type default)
			)
			(fill no)
			(layer "F.CrtYd")
		)
		(pad "1" smd rect
			(at 0.40005 0 180)
			(size 0.4572 0.508)
			(layers "F.Cu" "F.Mask" "F.Paste")
			(net "CPLD_UART_DTR_P3_N")
		)
		(pad "2" smd rect
			(at -0.40005 0 180)
			(size 0.4572 0.508)
			(layers "F.Cu" "F.Mask" "F.Paste")
			(net "GND")
		)
	)
)
